# ZAIUS-LV CARD-DVT-X01-BOM-X00_20170420_Final.xls.xlsx — Summary (bom)
| PLATFORM SOURCING AND PSL COMPLIANCE |  |  |  |  |  |  |  |  |  |
| Platform Name: |  |  |  |  |  |  |  |  |  |
| REVISION HISTORY |  |  |  |  |  |  |  |  |  |
| BOM Revision: | ECR # | Revision Description | Originator | Date |  |  |  |  |  |
| X00 |  |  |  | 42844 |  |  |  |  |  |
| Commodity Sourcing | # of components (X00 BOM) | % of Total | # of components (X01 BOM) | % of Total | # of components (X02 BOM) | % of Total | # of components (RTS) | % of Total | Risk Mitigation Plans in Place |
| Sole Source |  |  |  |  |  |  |  |  |  |
| Single Source |  |  |  |  |  |  |  |  |  |
| Multiple |  |  |  |  |  |  |  |  | NA |
| Total |  |  |  |  |  |  |  |  | NA |
|  |  | # of components | # of components aligned with Customer PSL* | % PSL alignment |  |  |  |  |  |
| Class 1 (Customer Managed) |  |  |  |  |  |  |  |  |  |
| Class 2 (ODM Managed to Customer PSL) |  |  |  |  |  |  |  |  |  |
| All other components(ODM Managed to ODM PSL) |  |  |  |  |  |  |  |  |  |
| *RFQ and/or Contract will list requirements for complying with Customer's PSL |  |  |  |  |  |  |  |  |  |
| Reference for quotation |  |  |  |  |  |  |  |  |  |
